G04 ================== begin FILE IDENTIFICATION RECORD ==================*
G04 Layout Name:  13919-sa.brd*
G04 Film Name:    L3GND*
G04 File Format:  Gerber RS274X*
G04 File Origin:  Cadence Allegro 16.5-S039*
G04 Origin Date:  Fri Nov 22 15:27:05 2013*
G04 *
G04 Layer:  VIA CLASS/L3GND*
G04 Layer:  PIN/L3GND*
G04 Layer:  ETCH/L3GND*
G04 Layer:  DRAWING FORMAT/LAYER_L3GND*
G04 Layer:  DRAWING FORMAT/LAYER_PCB_STORY*
G04 *
G04 Offset:    (0.00 0.00)*
G04 Mirror:    No*
G04 Mode:      Negative*
G04 Rotation:  0*
G04 FullContactRelief:  No*
G04 UndefLineWidth:     6.00*
G04 ================== end FILE IDENTIFICATION RECORD ====================*
%FSLAX35Y35*MOIN*%
%IR0*IPPOS*OFA0.00000B0.00000*MIA0B0*SFA1.00000B1.00000*%
%ADD11C,.036*%
%ADD14C,.057*%
%AMMACRO10*
4,1,15,.00398,.00044,
.003999,.000208,
.004004,-.000025,
.003996,-.000258,
.00398,-.00044,
.00483,-.00129,
.004897,-.001007,
.004947,-.000721,
.004981,-.000432,
.004997,-.000141,
.004997,.000149,
.00498,.00044,
.004946,.000729,
.004895,.001015,
.00483,.00129,
.00398,.00044,
0.0*
4,1,15,.00044,-.00398,
.000208,-.003999,
-.000025,-.004004,
-.000258,-.003996,
-.00044,-.00398,
-.00129,-.00483,
-.001007,-.004897,
-.000721,-.004947,
-.000432,-.004981,
-.000141,-.004997,
.000149,-.004997,
.00044,-.00498,
.000729,-.004946,
.001015,-.004895,
.00129,-.00483,
.00044,-.00398,
0.0*
4,1,15,-.00398,-.00044,
-.003999,-.000208,
-.004004,.000025,
-.003996,.000258,
-.00398,.00044,
-.00483,.00129,
-.004897,.001007,
-.004947,.000721,
-.004981,.000432,
-.004997,.000141,
-.004997,-.000149,
-.00498,-.00044,
-.004946,-.000729,
-.004895,-.001015,
-.00483,-.00129,
-.00398,-.00044,
0.0*
4,1,15,-.00044,.00398,
-.000208,.003999,
.000025,.004004,
.000258,.003996,
.00044,.00398,
.00129,.00483,
.001007,.004897,
.000721,.004947,
.000432,.004981,
.000141,.004997,
-.000149,.004997,
-.00044,.00498,
-.000729,.004946,
-.001015,.004895,
-.00129,.00483,
-.00044,.00398,
0.0*
%
%ADD10MACRO10*%
%AMMACRO13*
4,1,19,.02211,.00797,
.022536,.006671,
.022886,.005349,
.023158,.00401,
.023352,.002656,
.023467,.001294,
.023503,-.000073,
.023459,-.001439,
.023335,-.002801,
.023133,-.004153,
.022852,-.005491,
.022494,-.00681,
.02211,-.00797,
.02594,-.0118,
.027595,-.007116,
.028411,-.002216,
.028365,.002751,
.027456,.007635,
.02594,.0118,
.02211,.00797,
180.*
4,1,19,.00797,-.02211,
.006671,-.022536,
.005349,-.022886,
.00401,-.023158,
.002656,-.023352,
.001294,-.023467,
-.000073,-.023503,
-.001439,-.023459,
-.002801,-.023335,
-.004153,-.023133,
-.005491,-.022852,
-.00681,-.022494,
-.00797,-.02211,
-.0118,-.02594,
-.007116,-.027595,
-.002216,-.028411,
.002751,-.028365,
.007635,-.027456,
.0118,-.02594,
.00797,-.02211,
180.*
4,1,19,-.02211,-.00797,
-.022536,-.006671,
-.022886,-.005349,
-.023158,-.00401,
-.023352,-.002656,
-.023467,-.001294,
-.023503,.000073,
-.023459,.001439,
-.023335,.002801,
-.023133,.004153,
-.022852,.005491,
-.022494,.00681,
-.02211,.00797,
-.02594,.0118,
-.027595,.007116,
-.028411,.002216,
-.028365,-.002751,
-.027456,-.007635,
-.02594,-.0118,
-.02211,-.00797,
180.*
4,1,19,-.00797,.02211,
-.006671,.022536,
-.005349,.022886,
-.00401,.023158,
-.002656,.023352,
-.001294,.023467,
.000073,.023503,
.001439,.023459,
.002801,.023335,
.004153,.023133,
.005491,.022852,
.00681,.022494,
.00797,.02211,
.0118,.02594,
.007116,.027595,
.002216,.028411,
-.002751,.028365,
-.007635,.027456,
-.0118,.02594,
-.00797,.02211,
180.*
%
%ADD13MACRO13*%
%ADD12C,.121*%
%ADD15C,.114*%
%ADD16C,.02*%
%ADD17C,.006*%
%ADD18C,.11004*%
%ADD19C,.11704*%
G75*
%LPD*%
G75*
G36*
G01X-6000Y-6000D02*
X380016D01*
Y112693D01*
X-6000D01*
Y-6000D01*
G37*
%LPC*%
G75*
G36*
G01X18502Y36724D02*
X18369Y36858D01*
X17359D01*
G03X17127Y36862I-236J-6937D01*
G01X3937D01*
G02X3004Y37795I0J933D01*
G01Y48361D01*
G02X3766Y48530I400J-1D01*
G03Y53190I4984J2330D01*
G02X3004Y53359I-362J170D01*
G01Y102756D01*
G02X3937Y103689I933J0D01*
G01X143701D01*
G02X144634Y102756I0J-933D01*
G03X150141Y95965I6941J0D01*
G01X150199Y95953D01*
X150332Y95819D01*
X151342D01*
G03X151574Y95815I236J6937D01*
G01X222442D01*
G03X222674Y95819I-4J6941D01*
G01X223684D01*
X223817Y95953D01*
X223875Y95965D01*
G03X229382Y102756I-1434J6791D01*
G02X230315Y103689I933J0D01*
G01X370079D01*
G02X371012Y102756I0J-933D01*
G01Y67815D01*
G02X370079Y66882I-933J0D01*
G01X356889D01*
G03X356657Y66878I4J-6941D01*
G01X355647D01*
X355514Y66744D01*
X355456Y66732D01*
G03X350099Y61375I1434J-6791D01*
G01X350087Y61317D01*
X349953Y61184D01*
Y60174D01*
G03X349949Y59942I6937J-236D01*
G01Y22000D01*
X311862D01*
Y29331D01*
G03X311858Y29560I-6744J-3D01*
G01Y30574D01*
X311719Y30713D01*
X311707Y30770D01*
G03X298529I-6589J-1439D01*
G01X298517Y30713D01*
X298378Y30574D01*
Y29560D01*
G03X298374Y29331I6740J-232D01*
G01Y22000D01*
X24067D01*
Y29922D01*
G03X24063Y30154I-6941J-4D01*
G01Y31164D01*
X23929Y31297D01*
X23917Y31355D01*
G03X18560Y36712I-6791J-1434D01*
G01X18502Y36724D01*
G37*
%LPD*%
G75*
G36*
G01X323141Y60423D02*
G02X327575Y55530I-503J-4911D01*
G01Y43287D01*
X327557Y43269D01*
X327549Y43198D01*
G02X323141Y38790I-4911J503D01*
G01X323070Y38782D01*
X323052Y38764D01*
X310413D01*
X310395Y38782D01*
X310324Y38790D01*
G02X305890Y43689I503J4911D01*
G01Y55926D01*
X305908Y55944D01*
X305916Y56015D01*
G02X310324Y60423I4911J-503D01*
G01X310395Y60431D01*
X310413Y60449D01*
X323052D01*
X323070Y60431D01*
X323141Y60423D01*
G37*
G36*
G01X279923Y43269D02*
X279905Y43287D01*
Y55926D01*
X279923Y55944D01*
X279931Y56015D01*
G02X284339Y60423I4911J-503D01*
G01X284410Y60431D01*
X284428Y60449D01*
X297067D01*
X297085Y60431D01*
X297156Y60423D01*
G02X301590Y55524I-503J-4911D01*
G01Y43287D01*
X301572Y43269D01*
X301564Y43198D01*
G02X297156Y38790I-4911J503D01*
G01X297085Y38782D01*
X297067Y38764D01*
X284428D01*
X284410Y38782D01*
X284339Y38790D01*
G02X279931Y43198I503J4911D01*
G01X279923Y43269D01*
G37*
G36*
G01X275580Y56015D02*
X275588Y55944D01*
X275606Y55926D01*
Y43287D01*
X275588Y43269D01*
X275580Y43198D01*
G02X271172Y38790I-4911J503D01*
G01X271101Y38782D01*
X271083Y38764D01*
X258444D01*
X258426Y38782D01*
X258355Y38790D01*
G02X253947Y43198I503J4911D01*
G01X253939Y43269D01*
X253921Y43287D01*
Y55926D01*
X253939Y55944D01*
X253947Y56015D01*
G02X258355Y60423I4911J-503D01*
G01X258426Y60431D01*
X258444Y60449D01*
X271083D01*
X271101Y60431D01*
X271172Y60423D01*
G02X275580Y56015I-503J-4911D01*
G37*
G54D18*
X8950Y97440D03*
X364570Y96910D03*
G54D19*
X16538Y78346D03*
X304528D03*
G54D11*
X30680Y42700D03*
X23720Y37880D03*
X30833Y58700D03*
X21533Y59100D03*
X17033Y53450D03*
X15633Y69500D03*
X25733Y53450D03*
X15333Y62700D03*
X343019Y32504D03*
X347544Y32400D03*
X344360Y43670D03*
X343700Y53890D03*
X340080Y47960D03*
X340010Y58570D03*
X354650Y89890D03*
X355770Y78680D03*
X357350Y72160D03*
G54D14*
X43308Y73426D03*
X39373Y65551D03*
X27558Y73426D03*
X23623Y65551D03*
X47243Y91141D03*
X35433Y83266D03*
X31498Y91141D03*
X106298Y73426D03*
X102363Y65551D03*
X90553Y73426D03*
X86613Y65551D03*
X74803Y73426D03*
X70868Y65551D03*
X59058Y73426D03*
X55118Y65551D03*
X110238Y91141D03*
X98428Y83266D03*
X94488Y91141D03*
X82678Y83266D03*
X78743Y91141D03*
X66928Y83266D03*
X62993Y91141D03*
X51183Y83266D03*
X169293Y73426D03*
X165353Y65551D03*
X153543Y73426D03*
X149608Y65551D03*
X137798Y73426D03*
X133858Y65551D03*
X122048Y73426D03*
X118113Y65551D03*
X161418Y83266D03*
X157483Y91141D03*
X145668Y83266D03*
X141733Y91141D03*
X129923Y83266D03*
X125983Y91141D03*
X114173Y83266D03*
X232283Y73426D03*
X228348Y65551D03*
X216538Y73426D03*
X212598Y65551D03*
X200788Y73426D03*
X196853Y65551D03*
X185038Y73426D03*
X181103Y65551D03*
X224408Y83266D03*
X220473Y91141D03*
X208663Y83266D03*
X204723Y91141D03*
X192913Y83266D03*
X188978Y91141D03*
X177168Y83266D03*
X173228Y91141D03*
X291338Y65551D03*
X279528Y73426D03*
X275593Y65551D03*
X263778Y73426D03*
X259843Y65551D03*
X248033Y73426D03*
X244093Y65551D03*
X287403Y83266D03*
X283463Y91141D03*
X271653Y83266D03*
X267718Y91141D03*
X255908Y83266D03*
X251968Y91141D03*
X240158Y83266D03*
X236223Y91141D03*
X350393Y73426D03*
X346458Y65551D03*
X342518Y73426D03*
X334648D03*
X330708Y65551D03*
X326773Y73426D03*
X322833Y65551D03*
X318898Y73426D03*
X314963Y65551D03*
X311023Y73426D03*
X295278D03*
X350393Y83266D03*
X346458Y91141D03*
X342518Y83266D03*
X334648D03*
X330708Y91141D03*
X322833D03*
X318898Y83266D03*
X314963Y91141D03*
X311023Y83266D03*
X299213Y91141D03*
G54D10*
X45633Y31600D03*
X38133Y31500D03*
X35363Y37960D03*
X108333Y31600D03*
X100733Y31500D03*
X92533D03*
X84233Y31400D03*
X77233Y31700D03*
X68633Y31400D03*
X60633Y31500D03*
X52733Y31400D03*
X163733Y31500D03*
X155433Y31600D03*
X147833Y31500D03*
X139733D03*
X132333Y31600D03*
X124233D03*
X116233Y31500D03*
X226933D03*
X219033Y31600D03*
X210633Y31500D03*
X202433Y31400D03*
X194933Y31600D03*
X188976Y31543D03*
X179133Y31600D03*
X171333D03*
X288533Y31020D03*
X280933Y31400D03*
X274433D03*
X266033Y31020D03*
X258233Y31300D03*
X249533Y31400D03*
X242333Y31600D03*
X234333Y31400D03*
X329633Y31100D03*
X338583Y32050D03*
X295275Y31658D03*
G54D13*
X47243Y65551D03*
X35433Y73426D03*
X31498Y65551D03*
X43308Y83266D03*
X39373Y91141D03*
X27558Y83266D03*
X23623Y91141D03*
X110238Y65551D03*
X98428Y73426D03*
X94488Y65551D03*
X82678Y73426D03*
X78743Y65551D03*
X66928Y73426D03*
X62993Y65551D03*
X51183Y73426D03*
X106298Y83266D03*
X102363Y91141D03*
X90553Y83266D03*
X86613Y91141D03*
X74803Y83266D03*
X70868Y91141D03*
X59058Y83266D03*
X55118Y91141D03*
X161418Y73426D03*
X157483Y65551D03*
X145668Y73426D03*
X141733Y65551D03*
X129923Y73426D03*
X125983Y65551D03*
X114173Y73426D03*
X169293Y83266D03*
X165353Y91141D03*
X153543Y83266D03*
X149608Y91141D03*
X137798Y83266D03*
X133858Y91141D03*
X122048Y83266D03*
X118113Y91141D03*
X224408Y73426D03*
X220473Y65551D03*
X208663Y73426D03*
X204723Y65551D03*
X192913Y73426D03*
X188978Y65551D03*
X177168Y73426D03*
X173228Y65551D03*
X232283Y83266D03*
X228348Y91141D03*
X216538Y83266D03*
X212598Y91141D03*
X200788Y83266D03*
X196853Y91141D03*
X185038Y83266D03*
X181103Y91141D03*
X287403Y73426D03*
X283463Y65551D03*
X271653Y73426D03*
X267718Y65551D03*
X255908Y73426D03*
X251968Y65551D03*
X240158Y73426D03*
X236223Y65551D03*
X291338Y91141D03*
X279528Y83266D03*
X275593Y91141D03*
X263778Y83266D03*
X259843Y91141D03*
X248033Y83266D03*
X244093Y91141D03*
X338583Y65551D03*
X299213D03*
X338583Y91141D03*
X326773Y83266D03*
X295278D03*
G54D12*
X16538Y78346D03*
X304528D03*
G54D15*
X8950Y97440D03*
X8750Y50860D03*
X-2462Y651994D03*
X364570Y96910D03*
X758452Y17317D03*
X755722Y677788D03*
%LPC*%
G75*
G54D16*
G01X-67189Y-77263D02*
G02I-12000J0D01*
G01X-72339D02*
G02I-6850J0D01*
G01X-79189Y-93263D02*
Y-61263D01*
G01X-63189Y-77263D02*
X-95189D01*
G01X-63189Y-93263D02*
Y-173263D01*
G01D02*
X1156611D01*
G01X-63189Y-93263D02*
X1156611D01*
G01X-63189Y-128763D02*
X1156611D01*
G01X369111Y-93263D02*
Y-173263D01*
G01X506611Y-93263D02*
Y-173263D01*
G01X621611Y-93263D02*
Y-173263D01*
G01X789111Y-93263D02*
Y-173263D01*
G01X959111Y-93263D02*
Y-173263D01*
G01X1156611Y-93263D02*
Y-173263D01*
G01X1184611Y-77263D02*
G02I-12000J0D01*
G01X1179461D02*
G02I-6850J0D01*
G01X1172611Y-93263D02*
Y-61263D01*
G01X1188611Y-77263D02*
X1156611D01*
G54D17*
G01X-44374Y-163263D02*
Y-145763D01*
G01X-35204D02*
Y-163263D01*
G01Y-154513D02*
X-44374D01*
G01X-22289Y-163263D02*
X-23599Y-162971D01*
X-24909Y-161805D01*
X-25783Y-159763D01*
X-26219Y-157430D01*
X-25783Y-155096D01*
X-24909Y-153055D01*
X-23599Y-151888D01*
X-22289Y-151597D01*
X-20979Y-151888D01*
X-19669Y-153055D01*
X-18796Y-155096D01*
X-18577Y-157430D01*
X-18796Y-159763D01*
X-19669Y-161805D01*
X-20979Y-162971D01*
X-22289Y-163263D01*
G01X-8501D02*
Y-151597D01*
G01Y-154513D02*
X-7627Y-153055D01*
X-6317Y-151888D01*
X-4571Y-151597D01*
X-3043Y-151888D01*
X-1732Y-153055D01*
X-1077Y-155096D01*
Y-163263D01*
G01X9436Y-155388D02*
X16423D01*
X15768Y-153346D01*
X14676Y-152180D01*
X13148Y-151597D01*
X11619Y-151888D01*
X10309Y-152763D01*
X9436Y-154805D01*
X8999Y-156555D01*
Y-158305D01*
X9436Y-160055D01*
X10528Y-161805D01*
X11838Y-162971D01*
X13366Y-163263D01*
X14894Y-162680D01*
X16423Y-160930D01*
G01X25626Y-168513D02*
X26936Y-169096D01*
X28683Y-168513D01*
X29774Y-167347D01*
X30648Y-165888D01*
X31957Y-161222D01*
X34796Y-151597D01*
G01X27809D02*
X31957Y-161222D01*
G01X66957Y-153930D02*
X67831Y-153055D01*
X68486Y-151597D01*
X68923Y-149554D01*
X68486Y-147805D01*
X67613Y-146638D01*
X66084Y-145763D01*
X60189D01*
Y-163263D01*
X67394D01*
X68923Y-162097D01*
X69796Y-160346D01*
X70233Y-158305D01*
X69796Y-156263D01*
X68486Y-154513D01*
X66957Y-153930D01*
X60189D01*
G01X86641Y-163263D02*
Y-151597D01*
G01Y-153638D02*
X85768Y-152472D01*
X84457Y-151888D01*
X82929Y-151597D01*
X81401Y-152180D01*
X80091Y-153346D01*
X79217Y-155096D01*
X78781Y-157430D01*
X79217Y-159763D01*
X80091Y-161513D01*
X81401Y-162680D01*
X82929Y-163263D01*
X84457Y-162971D01*
X85768Y-162097D01*
X86641Y-160930D01*
G01X104141Y-145763D02*
Y-163263D01*
G01Y-160639D02*
X103268Y-162097D01*
X101957Y-162971D01*
X100429Y-163263D01*
X98683Y-162680D01*
X97373Y-161222D01*
X96499Y-159472D01*
X96281Y-157430D01*
X96499Y-155388D01*
X97373Y-153638D01*
X98683Y-152180D01*
X100429Y-151597D01*
X101957Y-151888D01*
X103049Y-152472D01*
X104141Y-153638D01*
G01X114654Y-167638D02*
X116183Y-168805D01*
X117929Y-169096D01*
X119457Y-168805D01*
X120768Y-167347D01*
X121641Y-165305D01*
Y-151597D01*
G01Y-153930D02*
X120768Y-152763D01*
X119457Y-151888D01*
X117929Y-151597D01*
X116183Y-152180D01*
X115091Y-153346D01*
X114217Y-155388D01*
X113781Y-157430D01*
X113999Y-159180D01*
X114873Y-161222D01*
X116183Y-162680D01*
X117929Y-163263D01*
X119239Y-162971D01*
X120768Y-161805D01*
X121641Y-160639D01*
G01X131936Y-155388D02*
X138923D01*
X138268Y-153346D01*
X137176Y-152180D01*
X135648Y-151597D01*
X134119Y-151888D01*
X132809Y-152763D01*
X131936Y-154805D01*
X131499Y-156555D01*
Y-158305D01*
X131936Y-160055D01*
X133028Y-161805D01*
X134338Y-162971D01*
X135866Y-163263D01*
X137394Y-162680D01*
X138923Y-160930D01*
G01X149654Y-163263D02*
Y-151597D01*
G01Y-153930D02*
X150746Y-152763D01*
X151838Y-151888D01*
X153366Y-151597D01*
X154457Y-151888D01*
X155768Y-152763D01*
G01X183344Y-163263D02*
Y-145763D01*
X188803D01*
X190549Y-146638D01*
X191641Y-147805D01*
X192078Y-150138D01*
X191641Y-152472D01*
X190331Y-153930D01*
X188803Y-154805D01*
X183344D01*
G01X188803D02*
X192078Y-163263D01*
G01X205211Y-151597D02*
Y-163263D01*
G01Y-146930D02*
X204774Y-146638D01*
Y-146055D01*
X205211Y-145763D01*
X205648Y-146055D01*
Y-146638D01*
X205211Y-146930D01*
G01X219436Y-161222D02*
X220528Y-162388D01*
X222056Y-163263D01*
X223366D01*
X224676Y-162680D01*
X225549Y-161805D01*
X225986Y-160639D01*
X225768Y-158888D01*
X224894Y-158013D01*
X220964Y-156263D01*
X220091Y-154221D01*
X220528Y-152763D01*
X221401Y-151888D01*
X222711Y-151597D01*
X224021Y-151888D01*
X225331Y-152763D01*
G01X236936Y-155388D02*
X243923D01*
X243268Y-153346D01*
X242176Y-152180D01*
X240648Y-151597D01*
X239119Y-151888D01*
X237809Y-152763D01*
X236936Y-154805D01*
X236499Y-156555D01*
Y-158305D01*
X236936Y-160055D01*
X238028Y-161805D01*
X239338Y-162971D01*
X240866Y-163263D01*
X242394Y-162680D01*
X243923Y-160930D01*
G01X254654Y-163263D02*
Y-151597D01*
G01Y-153930D02*
X255746Y-152763D01*
X256838Y-151888D01*
X258366Y-151597D01*
X259457Y-151888D01*
X260768Y-152763D01*
G01X297514Y-147222D02*
X296204Y-146346D01*
X294676Y-145763D01*
X292929D01*
X290964Y-146638D01*
X289436Y-148096D01*
X288344Y-149847D01*
X287471Y-152763D01*
X287252Y-155388D01*
X287689Y-158013D01*
X288344Y-159763D01*
X289654Y-161513D01*
X291183Y-162680D01*
X292711Y-163263D01*
X294239D01*
X295768Y-162680D01*
X297078Y-161805D01*
X298170Y-160639D01*
G01X314141Y-163263D02*
Y-151597D01*
G01Y-153638D02*
X313268Y-152472D01*
X311957Y-151888D01*
X310429Y-151597D01*
X308901Y-152180D01*
X307591Y-153346D01*
X306717Y-155096D01*
X306281Y-157430D01*
X306717Y-159763D01*
X307591Y-161513D01*
X308901Y-162680D01*
X310429Y-163263D01*
X311957Y-162971D01*
X313268Y-162097D01*
X314141Y-160930D01*
G01X324654Y-163263D02*
Y-151597D01*
G01Y-153930D02*
X325746Y-152763D01*
X326838Y-151888D01*
X328366Y-151597D01*
X329457Y-151888D01*
X330768Y-152763D01*
G01X349141Y-145763D02*
Y-163263D01*
G01Y-160639D02*
X348268Y-162097D01*
X346957Y-162971D01*
X345429Y-163263D01*
X343683Y-162680D01*
X342373Y-161222D01*
X341499Y-159472D01*
X341281Y-157430D01*
X341499Y-155388D01*
X342373Y-153638D01*
X343683Y-152180D01*
X345429Y-151597D01*
X346957Y-151888D01*
X348049Y-152472D01*
X349141Y-153638D01*
G01X112034Y-118263D02*
Y-100763D01*
X117711Y-115346D01*
X123388Y-100763D01*
Y-118263D01*
G01X135211D02*
X133901Y-117971D01*
X132591Y-116805D01*
X131717Y-114763D01*
X131281Y-112430D01*
X131717Y-110096D01*
X132591Y-108055D01*
X133901Y-106888D01*
X135211Y-106597D01*
X136521Y-106888D01*
X137831Y-108055D01*
X138704Y-110096D01*
X138923Y-112430D01*
X138704Y-114763D01*
X137831Y-116805D01*
X136521Y-117971D01*
X135211Y-118263D01*
G01X156641Y-100763D02*
Y-118263D01*
G01Y-115639D02*
X155768Y-117097D01*
X154457Y-117971D01*
X152929Y-118263D01*
X151183Y-117680D01*
X149873Y-116222D01*
X148999Y-114472D01*
X148781Y-112430D01*
X148999Y-110388D01*
X149873Y-108638D01*
X151183Y-107180D01*
X152929Y-106597D01*
X154457Y-106888D01*
X155549Y-107472D01*
X156641Y-108638D01*
G01X166936Y-110388D02*
X173923D01*
X173268Y-108346D01*
X172176Y-107180D01*
X170648Y-106597D01*
X169119Y-106888D01*
X167809Y-107763D01*
X166936Y-109805D01*
X166499Y-111555D01*
Y-113305D01*
X166936Y-115055D01*
X168028Y-116805D01*
X169338Y-117971D01*
X170866Y-118263D01*
X172394Y-117680D01*
X173923Y-115930D01*
G01X187711Y-118263D02*
Y-100763D01*
G01X402811Y-163263D02*
Y-145763D01*
X400191Y-149263D01*
G01Y-163263D02*
X405431D01*
G01X415508Y-159763D02*
X416817Y-161805D01*
X418564Y-162971D01*
X420529Y-163263D01*
X422276Y-162971D01*
X424023Y-161513D01*
X425114Y-159763D01*
X425333Y-158013D01*
X424896Y-155972D01*
X423368Y-154513D01*
X421839Y-153930D01*
X419874D01*
G01X421839D02*
X423149Y-153055D01*
X424241Y-151597D01*
X424678Y-149847D01*
X424241Y-148096D01*
X423149Y-146638D01*
X421184Y-145763D01*
X419219Y-146055D01*
X417254Y-147222D01*
G01X434099Y-161222D02*
X435628Y-162680D01*
X437374Y-163263D01*
X439121Y-162680D01*
X440649Y-160930D01*
X441741Y-158305D01*
X442178Y-155680D01*
Y-152472D01*
X441741Y-149847D01*
X440649Y-147513D01*
X439339Y-146346D01*
X437811Y-145763D01*
X436064Y-146346D01*
X434754Y-147513D01*
X433881Y-149263D01*
X433444Y-151597D01*
X433881Y-153638D01*
X434973Y-155680D01*
X436283Y-156847D01*
X437811Y-157138D01*
X439557Y-156555D01*
X440868Y-155096D01*
X442178Y-152472D01*
G01X455311Y-163263D02*
Y-145763D01*
X452691Y-149263D01*
G01Y-163263D02*
X457931D01*
G01X469099Y-161222D02*
X470628Y-162680D01*
X472374Y-163263D01*
X474121Y-162680D01*
X475649Y-160930D01*
X476741Y-158305D01*
X477178Y-155680D01*
Y-152472D01*
X476741Y-149847D01*
X475649Y-147513D01*
X474339Y-146346D01*
X472811Y-145763D01*
X471064Y-146346D01*
X469754Y-147513D01*
X468881Y-149263D01*
X468444Y-151597D01*
X468881Y-153638D01*
X469973Y-155680D01*
X471283Y-156847D01*
X472811Y-157138D01*
X474557Y-156555D01*
X475868Y-155096D01*
X477178Y-152472D01*
G01X389694Y-118263D02*
Y-100763D01*
X394934D01*
X396681Y-101638D01*
X397991Y-103680D01*
X398428Y-106013D01*
X397991Y-108346D01*
X396899Y-110096D01*
X394934Y-110972D01*
X389694D01*
G01X416364Y-102222D02*
X415054Y-101346D01*
X413526Y-100763D01*
X411779D01*
X409814Y-101638D01*
X408286Y-103096D01*
X407194Y-104847D01*
X406321Y-107763D01*
X406102Y-110388D01*
X406539Y-113013D01*
X407194Y-114763D01*
X408504Y-116513D01*
X410033Y-117680D01*
X411561Y-118263D01*
X413089D01*
X414618Y-117680D01*
X415928Y-116805D01*
X417020Y-115639D01*
G01X430807Y-108930D02*
X431681Y-108055D01*
X432336Y-106597D01*
X432773Y-104554D01*
X432336Y-102805D01*
X431463Y-101638D01*
X429934Y-100763D01*
X424039D01*
Y-118263D01*
X431244D01*
X432773Y-117097D01*
X433646Y-115346D01*
X434083Y-113305D01*
X433646Y-111263D01*
X432336Y-109513D01*
X430807Y-108930D01*
X424039D01*
G01X440011Y-124096D02*
X453111D01*
G01X459039Y-118263D02*
Y-100763D01*
X469083Y-118263D01*
Y-100763D01*
G01X481561Y-118263D02*
X479814Y-117971D01*
X478286Y-116805D01*
X476976Y-115055D01*
X476102Y-113013D01*
X475666Y-110680D01*
Y-108346D01*
X476102Y-106013D01*
X476976Y-103971D01*
X478286Y-102222D01*
X479814Y-101055D01*
X481561Y-100763D01*
X483307Y-101055D01*
X484836Y-102222D01*
X486146Y-103971D01*
X487020Y-106013D01*
X487456Y-108346D01*
Y-110680D01*
X487020Y-113013D01*
X486146Y-115055D01*
X484836Y-116805D01*
X483307Y-117971D01*
X481561Y-118263D01*
G01X532402Y-100763D02*
X537861Y-118263D01*
X543320Y-100763D01*
G01X559728Y-118263D02*
X550994D01*
Y-100763D01*
X559728D01*
G01X556234Y-109221D02*
X550994D01*
G01X568494Y-118263D02*
Y-100763D01*
X573953D01*
X575699Y-101638D01*
X576791Y-102805D01*
X577228Y-105138D01*
X576791Y-107472D01*
X575481Y-108930D01*
X573953Y-109805D01*
X568494D01*
G01X573953D02*
X577228Y-118263D01*
G01X590361Y-118846D02*
X589924Y-118555D01*
Y-117971D01*
X590361Y-117680D01*
X590798Y-117971D01*
Y-118555D01*
X590361Y-118846D01*
G01X550776Y-160930D02*
X552523Y-162388D01*
X554488Y-163263D01*
X556234D01*
X557981Y-162388D01*
X559291Y-160930D01*
X559946Y-158888D01*
X559509Y-156847D01*
X558418Y-155096D01*
X556453Y-153930D01*
X553833Y-153346D01*
X552304Y-152180D01*
X551649Y-150138D01*
X552086Y-148096D01*
X553178Y-146638D01*
X554706Y-145763D01*
X556234D01*
X557763Y-146346D01*
X559073Y-147805D01*
G01X567402Y-163263D02*
X572861Y-145763D01*
X578320Y-163263D01*
G01X576354Y-157138D02*
X569367D01*
G01X744678Y-145763D02*
Y-163263D01*
X735944D01*
G01X727614Y-159763D02*
X726305Y-161805D01*
X724558Y-162971D01*
X722593Y-163263D01*
X720846Y-162971D01*
X719099Y-161513D01*
X718008Y-159763D01*
X717789Y-158013D01*
X718226Y-155972D01*
X719754Y-154513D01*
X721283Y-153930D01*
X723248D01*
G01X721283D02*
X719973Y-153055D01*
X718881Y-151597D01*
X718444Y-149847D01*
X718881Y-148096D01*
X719973Y-146638D01*
X721938Y-145763D01*
X723903Y-146055D01*
X725868Y-147222D01*
G01X704001Y-154513D02*
X699634D01*
Y-159763D01*
X700944Y-161513D01*
X702473Y-162680D01*
X704656Y-163263D01*
X706839Y-162680D01*
X708368Y-161513D01*
X709678Y-159763D01*
X710551Y-157721D01*
X710988Y-155388D01*
Y-153346D01*
X710551Y-151597D01*
X709678Y-149554D01*
X708368Y-147805D01*
X707058Y-146638D01*
X705311Y-145763D01*
X703783D01*
X702036Y-146346D01*
X700726Y-147513D01*
G01X692833Y-163263D02*
Y-145763D01*
X682789Y-163263D01*
Y-145763D01*
G01X675114Y-163263D02*
Y-145763D01*
X670748D01*
X669001Y-146638D01*
X667691Y-147805D01*
X666599Y-149554D01*
X665726Y-151597D01*
X665508Y-154513D01*
X665726Y-157430D01*
X666599Y-159472D01*
X667691Y-161222D01*
X669001Y-162388D01*
X670748Y-163263D01*
X675114D01*
G01X665944Y-100763D02*
Y-118263D01*
X674678D01*
G01X691741D02*
Y-106597D01*
G01Y-108638D02*
X690868Y-107472D01*
X689557Y-106888D01*
X688029Y-106597D01*
X686501Y-107180D01*
X685191Y-108346D01*
X684317Y-110096D01*
X683881Y-112430D01*
X684317Y-114763D01*
X685191Y-116513D01*
X686501Y-117680D01*
X688029Y-118263D01*
X689557Y-117971D01*
X690868Y-117097D01*
X691741Y-115930D01*
G01X700726Y-123513D02*
X702036Y-124096D01*
X703783Y-123513D01*
X704874Y-122347D01*
X705748Y-120888D01*
X707057Y-116222D01*
X709896Y-106597D01*
G01X702909D02*
X707057Y-116222D01*
G01X719536Y-110388D02*
X726523D01*
X725868Y-108346D01*
X724776Y-107180D01*
X723248Y-106597D01*
X721719Y-106888D01*
X720409Y-107763D01*
X719536Y-109805D01*
X719099Y-111555D01*
Y-113305D01*
X719536Y-115055D01*
X720628Y-116805D01*
X721938Y-117971D01*
X723466Y-118263D01*
X724994Y-117680D01*
X726523Y-115930D01*
G01X737254Y-118263D02*
Y-106597D01*
G01Y-108930D02*
X738346Y-107763D01*
X739438Y-106888D01*
X740966Y-106597D01*
X742057Y-106888D01*
X743368Y-107763D01*
G01X808058Y-118263D02*
Y-100763D01*
X812424D01*
X814171Y-101638D01*
X815481Y-102805D01*
X816573Y-104554D01*
X817446Y-106597D01*
X817664Y-109513D01*
X817446Y-112430D01*
X816573Y-114472D01*
X815481Y-116222D01*
X814171Y-117388D01*
X812424Y-118263D01*
X808058D01*
G01X827086Y-110388D02*
X834073D01*
X833418Y-108346D01*
X832326Y-107180D01*
X830798Y-106597D01*
X829269Y-106888D01*
X827959Y-107763D01*
X827086Y-109805D01*
X826649Y-111555D01*
Y-113305D01*
X827086Y-115055D01*
X828178Y-116805D01*
X829488Y-117971D01*
X831016Y-118263D01*
X832544Y-117680D01*
X834073Y-115930D01*
G01X844586Y-116222D02*
X845678Y-117388D01*
X847206Y-118263D01*
X848516D01*
X849826Y-117680D01*
X850699Y-116805D01*
X851136Y-115639D01*
X850918Y-113888D01*
X850044Y-113013D01*
X846114Y-111263D01*
X845241Y-109221D01*
X845678Y-107763D01*
X846551Y-106888D01*
X847861Y-106597D01*
X849171Y-106888D01*
X850481Y-107763D01*
G01X865361Y-106597D02*
Y-118263D01*
G01Y-101930D02*
X864924Y-101638D01*
Y-101055D01*
X865361Y-100763D01*
X865798Y-101055D01*
Y-101638D01*
X865361Y-101930D01*
G01X879804Y-122638D02*
X881333Y-123805D01*
X883079Y-124096D01*
X884607Y-123805D01*
X885918Y-122347D01*
X886791Y-120305D01*
Y-106597D01*
G01Y-108930D02*
X885918Y-107763D01*
X884607Y-106888D01*
X883079Y-106597D01*
X881333Y-107180D01*
X880241Y-108346D01*
X879367Y-110388D01*
X878931Y-112430D01*
X879149Y-114180D01*
X880023Y-116222D01*
X881333Y-117680D01*
X883079Y-118263D01*
X884389Y-117971D01*
X885918Y-116805D01*
X886791Y-115639D01*
G01X896649Y-118263D02*
Y-106597D01*
G01Y-109513D02*
X897523Y-108055D01*
X898833Y-106888D01*
X900579Y-106597D01*
X902107Y-106888D01*
X903418Y-108055D01*
X904073Y-110096D01*
Y-118263D01*
G01X914586Y-110388D02*
X921573D01*
X920918Y-108346D01*
X919826Y-107180D01*
X918298Y-106597D01*
X916769Y-106888D01*
X915459Y-107763D01*
X914586Y-109805D01*
X914149Y-111555D01*
Y-113305D01*
X914586Y-115055D01*
X915678Y-116805D01*
X916988Y-117971D01*
X918516Y-118263D01*
X920044Y-117680D01*
X921573Y-115930D01*
G01X932304Y-118263D02*
Y-106597D01*
G01Y-108930D02*
X933396Y-107763D01*
X934488Y-106888D01*
X936016Y-106597D01*
X937107Y-106888D01*
X938418Y-107763D01*
G01X853991Y-145763D02*
X859231D01*
G01X856611D02*
Y-163263D01*
G01X853991D02*
X859231D01*
G01X868652Y-145763D02*
X874111Y-163263D01*
X879570Y-145763D01*
G01X891611Y-163263D02*
Y-155388D01*
X887244Y-145763D01*
G01X895978D02*
X891611Y-155388D01*
G01X979061Y-163263D02*
Y-145763D01*
X976441Y-149263D01*
G01Y-163263D02*
X981681D01*
G01X996561D02*
Y-145763D01*
X993941Y-149263D01*
G01Y-163263D02*
X999181D01*
G01X1010131Y-163846D02*
X1017991Y-145763D01*
G01X1027413Y-148680D02*
X1028723Y-146930D01*
X1030251Y-146055D01*
X1031998Y-145763D01*
X1034181Y-146346D01*
X1035709Y-147805D01*
X1036146Y-149554D01*
X1035928Y-151305D01*
X1035054Y-152763D01*
X1030688Y-155680D01*
X1028723Y-157721D01*
X1027413Y-160639D01*
X1026976Y-163263D01*
X1036146D01*
G01X1044913Y-148680D02*
X1046223Y-146930D01*
X1047751Y-146055D01*
X1049498Y-145763D01*
X1051681Y-146346D01*
X1053209Y-147805D01*
X1053646Y-149554D01*
X1053428Y-151305D01*
X1052554Y-152763D01*
X1048188Y-155680D01*
X1046223Y-157721D01*
X1044913Y-160639D01*
X1044476Y-163263D01*
X1053646D01*
G01X1062631Y-163846D02*
X1070491Y-145763D01*
G01X1079913Y-148680D02*
X1081223Y-146930D01*
X1082751Y-146055D01*
X1084498Y-145763D01*
X1086681Y-146346D01*
X1088209Y-147805D01*
X1088646Y-149554D01*
X1088428Y-151305D01*
X1087554Y-152763D01*
X1083188Y-155680D01*
X1081223Y-157721D01*
X1079913Y-160639D01*
X1079476Y-163263D01*
X1088646D01*
G01X1101561Y-145763D02*
X1099814Y-146346D01*
X1098504Y-147805D01*
X1097631Y-149554D01*
X1096976Y-151888D01*
X1096758Y-154513D01*
X1096976Y-157138D01*
X1097631Y-159472D01*
X1098504Y-161222D01*
X1099814Y-162680D01*
X1101561Y-163263D01*
X1103307Y-162680D01*
X1104618Y-161222D01*
X1105491Y-159472D01*
X1106146Y-157138D01*
X1106364Y-154513D01*
X1106146Y-151888D01*
X1105491Y-149554D01*
X1104618Y-147805D01*
X1103307Y-146346D01*
X1101561Y-145763D01*
G01X1119061Y-163263D02*
Y-145763D01*
X1116441Y-149263D01*
G01Y-163263D02*
X1121681D01*
G01X1131758Y-159763D02*
X1133067Y-161805D01*
X1134814Y-162971D01*
X1136779Y-163263D01*
X1138526Y-162971D01*
X1140273Y-161513D01*
X1141364Y-159763D01*
X1141583Y-158013D01*
X1141146Y-155972D01*
X1139618Y-154513D01*
X1138089Y-153930D01*
X1136124D01*
G01X1138089D02*
X1139399Y-153055D01*
X1140491Y-151597D01*
X1140928Y-149847D01*
X1140491Y-148096D01*
X1139399Y-146638D01*
X1137434Y-145763D01*
X1135469Y-146055D01*
X1133504Y-147222D01*
G01X1026758Y-118263D02*
Y-100763D01*
X1031124D01*
X1032871Y-101638D01*
X1034181Y-102805D01*
X1035273Y-104554D01*
X1036146Y-106597D01*
X1036364Y-109513D01*
X1036146Y-112430D01*
X1035273Y-114472D01*
X1034181Y-116222D01*
X1032871Y-117388D01*
X1031124Y-118263D01*
X1026758D01*
G01X1052991D02*
Y-106597D01*
G01Y-108638D02*
X1052118Y-107472D01*
X1050807Y-106888D01*
X1049279Y-106597D01*
X1047751Y-107180D01*
X1046441Y-108346D01*
X1045567Y-110096D01*
X1045131Y-112430D01*
X1045567Y-114763D01*
X1046441Y-116513D01*
X1047751Y-117680D01*
X1049279Y-118263D01*
X1050807Y-117971D01*
X1052118Y-117097D01*
X1052991Y-115930D01*
G01X1066561Y-100763D02*
Y-118263D01*
G01X1063504Y-106597D02*
X1069618D01*
G01X1080786Y-110388D02*
X1087773D01*
X1087118Y-108346D01*
X1086026Y-107180D01*
X1084498Y-106597D01*
X1082969Y-106888D01*
X1081659Y-107763D01*
X1080786Y-109805D01*
X1080349Y-111555D01*
Y-113305D01*
X1080786Y-115055D01*
X1081878Y-116805D01*
X1083188Y-117971D01*
X1084716Y-118263D01*
X1086244Y-117680D01*
X1087773Y-115930D01*
M02*
